(kicad_pcb
	(version 20260206)
	(generator "pcbnew")
	(generator_version "10.0")
	(general
		(thickness 1.6)
		(legacy_teardrops no)
	)
	(paper "A4")
	(title_block
		(title "03242023_DA0F0TMBIJ0_F0T_Motherboard_J_brd_V01_OCP.brd")
		(comment 1 "Grand Teton / footprints 416-422 of 6105")
	)
	(layers
		(0 "F.Cu" signal "TOP")
		(4 "In1.Cu" signal "GND")
		(6 "In2.Cu" signal "IN1")
		(8 "In3.Cu" signal "GND1")
		(10 "In4.Cu" signal "IN2")
		(12 "In5.Cu" signal "GND2")
		(14 "In6.Cu" signal "IN3")
		(16 "In7.Cu" signal "GND3")
		(18 "In8.Cu" signal "VCC")
		(20 "In9.Cu" signal "VCC1")
		(22 "In10.Cu" signal "GND4")
		(24 "In11.Cu" signal "IN4")
		(26 "In12.Cu" signal "GND5")
		(28 "In13.Cu" signal "IN5")
		(30 "In14.Cu" signal "GND6")
		(32 "In15.Cu" signal "IN6")
		(34 "In16.Cu" signal "GND7")
		(2 "B.Cu" signal "BOTTOM")
		(9 "F.Adhes" user "F.Adhesive")
		(11 "B.Adhes" user "B.Adhesive")
		(13 "F.Paste" user "Package Geometry/Pastemask Top")
		(15 "B.Paste" user "Package Geometry/Pastemask Bottom")
		(5 "F.SilkS" user "Ref Des/Silkscreen Top")
		(7 "B.SilkS" user "Ref Des/Silkscreen Bottom")
		(1 "F.Mask" user "Board Geometry/Soldermask Top")
		(3 "B.Mask" user "Board Geometry/Soldermask Bottom")
		(17 "Dwgs.User" user "User.Drawings")
		(19 "Cmts.User" user "User.Comments")
		(21 "Eco1.User" user "User.Eco1")
		(23 "Eco2.User" user "User.Eco2")
		(25 "Edge.Cuts" user "Board Geometry/Outline")
		(27 "Margin" user)
		(31 "F.CrtYd" user "Package Geometry/Place Bound Top")
		(29 "B.CrtYd" user "Package Geometry/Place Bound Bottom")
		(35 "F.Fab" user "Ref Des/Assembly Top")
		(33 "B.Fab" user "Ref Des/Assembly Bottom")
	)
	(footprint ""
		(layer "F.Cu")
		(at 424.98772 -51.22418 180)
		(property "Reference" "C2360"
			(at 0 0 180)
			(layer "F.SilkS")
			(hide yes)
			(effects
				(font
					(size 1.27 1.27)
				)
			)
		)
		(property "Value" ""
			(at 0 0 180)
			(layer "F.Fab")
			(effects
				(font
					(size 1.27 1.27)
				)
			)
		)
		(duplicate_pad_numbers_are_jumpers no)
		(fp_line
			(start 0.7874 0.4064)
			(end -0.7874 0.4064)
			(stroke
				(width 0.1524)
				(type default)
			)
			(layer "F.SilkS")
		)
		(fp_line
			(start 0.7874 -0.4064)
			(end 0.7874 0.4064)
			(stroke
				(width 0.1524)
				(type default)
			)
			(layer "F.SilkS")
		)
		(fp_line
			(start -0.7874 0.4064)
			(end -0.7874 -0.4064)
			(stroke
				(width 0.1524)
				(type default)
			)
			(layer "F.SilkS")
		)
		(fp_line
			(start -0.7874 -0.4064)
			(end 0.7874 -0.4064)
			(stroke
				(width 0.1524)
				(type default)
			)
			(layer "F.SilkS")
		)
		(fp_line
			(start 0.6858 0.3048)
			(end 0.1016 0.3048)
			(stroke
				(width 0.1)
				(type default)
			)
			(layer "F.Fab")
		)
		(fp_line
			(start 0.6858 -0.3048)
			(end 0.6858 0.3048)
			(stroke
				(width 0.1)
				(type default)
			)
			(layer "F.Fab")
		)
		(fp_line
			(start 0.1016 0.3048)
			(end 0.1016 0.2794)
			(stroke
				(width 0.1)
				(type default)
			)
			(layer "F.Fab")
		)
		(fp_line
			(start 0.1016 0.2794)
			(end -0.1016 0.2794)
			(stroke
				(width 0.1)
				(type default)
			)
			(layer "F.Fab")
		)
		(fp_line
			(start 0.1016 -0.2794)
			(end 0.1016 -0.3048)
			(stroke
				(width 0.1)
				(type default)
			)
			(layer "F.Fab")
		)
		(fp_line
			(start 0.1016 -0.3048)
			(end 0.6858 -0.3048)
			(stroke
				(width 0.1)
				(type default)
			)
			(layer "F.Fab")
		)
		(fp_line
			(start -0.1016 0.3048)
			(end -0.6858 0.3048)
			(stroke
				(width 0.1)
				(type default)
			)
			(layer "F.Fab")
		)
		(fp_line
			(start -0.1016 0.2794)
			(end -0.1016 0.3048)
			(stroke
				(width 0.1)
				(type default)
			)
			(layer "F.Fab")
		)
		(fp_line
			(start -0.1016 -0.2794)
			(end 0.1016 -0.2794)
			(stroke
				(width 0.1)
				(type default)
			)
			(layer "F.Fab")
		)
		(fp_line
			(start -0.1016 -0.3048)
			(end -0.1016 -0.2794)
			(stroke
				(width 0.1)
				(type default)
			)
			(layer "F.Fab")
		)
		(fp_line
			(start -0.6858 0.3048)
			(end -0.6858 -0.3048)
			(stroke
				(width 0.1)
				(type default)
			)
			(layer "F.Fab")
		)
		(fp_line
			(start -0.6858 -0.3048)
			(end -0.1016 -0.3048)
			(stroke
				(width 0.1)
				(type default)
			)
			(layer "F.Fab")
		)
		(pad "1" smd rect
			(at -0.40005 0)
			(size 0.4572 0.508)
			(layers "F.Cu" "F.Mask" "F.Paste")
			(net "P3V3")
		)
		(pad "2" smd rect
			(at 0.40005 0)
			(size 0.4572 0.508)
			(layers "F.Cu" "F.Mask" "F.Paste")
			(net "GND")
		)
	)
	(footprint ""
		(layer "F.Cu")
		(at 85.576156 -92.888308)
		(property "Reference" "Q80"
			(at -4.63804 -0.635508 0)
			(unlocked yes)
			(layer "F.SilkS")
			(effects
				(font
					(size 0.7874 0.5842)
					(thickness 0.1524)
				)
				(justify left)
			)
		)
		(property "Value" ""
			(at 0 0 0)
			(layer "F.Fab")
			(effects
				(font
					(size 1.27 1.27)
				)
			)
		)
		(duplicate_pad_numbers_are_jumpers no)
		(fp_line
			(start -1.332738 -1.100074)
			(end -0.4826 -1.100074)
			(stroke
				(width 0.1524)
				(type default)
			)
			(layer "F.SilkS")
		)
		(fp_line
			(start -1.332738 1.100074)
			(end -1.332738 -1.100074)
			(stroke
				(width 0.1524)
				(type default)
			)
			(layer "F.SilkS")
		)
		(fp_line
			(start -0.4826 -1.100074)
			(end 0 -0.541274)
			(stroke
				(width 0.1524)
				(type default)
			)
			(layer "F.SilkS")
		)
		(fp_line
			(start 0 -0.541274)
			(end 0.4826 -1.100074)
			(stroke
				(width 0.1524)
				(type default)
			)
			(layer "F.SilkS")
		)
		(fp_line
			(start 0.4826 -1.100074)
			(end 1.332738 -1.100074)
			(stroke
				(width 0.1524)
				(type default)
			)
			(layer "F.SilkS")
		)
		(fp_line
			(start 1.332738 -1.100074)
			(end 1.332738 1.100074)
			(stroke
				(width 0.1524)
				(type default)
			)
			(layer "F.SilkS")
		)
		(fp_line
			(start 1.332738 1.100074)
			(end -1.332738 1.100074)
			(stroke
				(width 0.1524)
				(type default)
			)
			(layer "F.SilkS")
		)
		(fp_poly
			(pts
				(xy -2.2352 -1.001014) (xy -1.533144 -0.649986) (xy -2.2352 -0.298958)
			)
			(stroke
				(width 0)
				(type default)
			)
			(fill yes)
			(layer "F.SilkS")
		)
		(fp_line
			(start -0.674878 -1.100074)
			(end 0.674878 -1.100074)
			(stroke
				(width 0.1)
				(type default)
			)
			(layer "F.Fab")
		)
		(fp_line
			(start -0.674878 1.100074)
			(end -0.674878 -1.100074)
			(stroke
				(width 0.1)
				(type default)
			)
			(layer "F.Fab")
		)
		(fp_line
			(start 0.674878 -1.100074)
			(end 0.674878 1.100074)
			(stroke
				(width 0.1)
				(type default)
			)
			(layer "F.Fab")
		)
		(fp_line
			(start 0.674878 1.100074)
			(end -0.674878 1.100074)
			(stroke
				(width 0.1)
				(type default)
			)
			(layer "F.Fab")
		)
		(fp_poly
			(pts
				(xy -2.2352 -0.298958) (xy -2.2352 -1.001014) (xy -1.533144 -0.649986)
			)
			(stroke
				(width 0)
				(type default)
			)
			(fill yes)
			(layer "F.Fab")
		)
		(pad "1" smd rect
			(at -0.94996 -0.649986 90)
			(size 0.4318 0.508)
			(layers "F.Cu" "F.Mask" "F.Paste")
			(net "GND")
		)
		(pad "2" smd rect
			(at -0.94996 0 90)
			(size 0.4318 0.508)
			(layers "F.Cu" "F.Mask" "F.Paste")
			(net "PWRGD_PVCCFA_EHV_CPU0")
		)
		(pad "3" smd rect
			(at -0.94996 0.649986 90)
			(size 0.4318 0.508)
			(layers "F.Cu" "F.Mask" "F.Paste")
			(net "LED_PWRGD_PVCCFA_EHV_FIVRA_CP_1")
		)
		(pad "4" smd rect
			(at 0.94996 0.649986 90)
			(size 0.4318 0.508)
			(layers "F.Cu" "F.Mask" "F.Paste")
			(net "GND")
		)
		(pad "5" smd rect
			(at 0.94996 0 90)
			(size 0.4318 0.508)
			(layers "F.Cu" "F.Mask" "F.Paste")
			(net "PWRGD_PVCCFA_EHV_FIVRA_CPU0")
		)
		(pad "6" smd rect
			(at 0.94996 -0.649986 90)
			(size 0.4318 0.508)
			(layers "F.Cu" "F.Mask" "F.Paste")
			(net "LED_PWRGD_PVCCFA_EHV_CPU0_D")
		)
	)
	(footprint ""
		(layer "F.Cu")
		(at 421.0558 -17.612614 90)
		(property "Reference" "C860"
			(at 0 0 90)
			(layer "F.SilkS")
			(hide yes)
			(effects
				(font
					(size 1.27 1.27)
				)
			)
		)
		(property "Value" ""
			(at 0 0 90)
			(layer "F.Fab")
			(effects
				(font
					(size 1.27 1.27)
				)
			)
		)
		(duplicate_pad_numbers_are_jumpers no)
		(fp_line
			(start 0.299974 -0.150114)
			(end 0.299974 0.150114)
			(stroke
				(width 0.1)
				(type default)
			)
			(layer "F.Fab")
		)
		(fp_line
			(start -0.299974 -0.150114)
			(end 0.299974 -0.150114)
			(stroke
				(width 0.1)
				(type default)
			)
			(layer "F.Fab")
		)
		(fp_line
			(start 0.299974 0.150114)
			(end -0.299974 0.150114)
			(stroke
				(width 0.1)
				(type default)
			)
			(layer "F.Fab")
		)
		(fp_line
			(start -0.299974 0.150114)
			(end -0.299974 -0.150114)
			(stroke
				(width 0.1)
				(type default)
			)
			(layer "F.Fab")
		)
		(pad "1" smd rect
			(at -0.2667 0 90)
			(size 0.3048 0.381)
			(layers "F.Cu" "F.Mask" "F.Paste")
			(net "P5E_CPU0_PE1_TX_C_DN<4>")
		)
		(pad "2" smd rect
			(at 0.2667 0 90)
			(size 0.3048 0.381)
			(layers "F.Cu" "F.Mask" "F.Paste")
			(net "P5E_CPU0_PE1_TX_DN<4>")
		)
	)
	(footprint ""
		(layer "F.Cu")
		(at 429.267112 -143.1671 -90)
		(property "Reference" "PJ45"
			(at -1.386078 -1.278128 0)
			(unlocked yes)
			(layer "F.SilkS")
			(effects
				(font
					(size 0.7874 0.5842)
					(thickness 0.1524)
				)
				(justify left)
			)
		)
		(property "Value" ""
			(at 0 0 270)
			(layer "F.Fab")
			(effects
				(font
					(size 1.27 1.27)
				)
			)
		)
		(duplicate_pad_numbers_are_jumpers no)
		(pad "1" smd circle
			(at -0.7493 0)
			(size 0 0)
			(layers "F.Cu" "F.Mask" "F.Paste")
			(net "VSENSE_PVCCINFAON_CPU0_DP")
		)
		(pad "2" smd rect
			(at 0.7493 0 180)
			(size 0.7112 0.8128)
			(layers "F.Cu" "F.Mask" "F.Paste")
			(net "SH_PVCCINFAON_CPU0")
		)
		(zone
			(layer "F.Cu")
			(hatch none 0.5)
			(connect_pads
				(clearance 0)
			)
			(min_thickness 0.25)
			(keepout
				(tracks allowed)
				(vias not_allowed)
				(pads allowed)
				(copperpour not_allowed)
				(footprints allowed)
			)
			(placement
				(enabled no)
				(sheetname "")
			)
			(fill
				(thermal_gap 0.5)
				(thermal_bridge_width 0.5)
				(island_removal_mode 0)
			)
			(polygon
				(pts
					(xy 428.855886 -141.9606) (xy 429.673512 -141.9606) (xy 429.673512 -144.3482) (xy 428.855886 -144.3482)
				)
			)
		)
	)
	(footprint ""
		(layer "F.Cu")
		(at 50.437542 -158.211266)
		(property "Reference" "PC446"
			(at 0 0 0)
			(layer "F.SilkS")
			(hide yes)
			(effects
				(font
					(size 1.27 1.27)
				)
			)
		)
		(property "Value" ""
			(at 0 0 0)
			(layer "F.Fab")
			(effects
				(font
					(size 1.27 1.27)
				)
			)
		)
		(duplicate_pad_numbers_are_jumpers no)
		(fp_line
			(start -0.7874 -0.4064)
			(end 0.7874 -0.4064)
			(stroke
				(width 0.1524)
				(type default)
			)
			(layer "F.SilkS")
		)
		(fp_line
			(start -0.7874 0.4064)
			(end -0.7874 -0.4064)
			(stroke
				(width 0.1524)
				(type default)
			)
			(layer "F.SilkS")
		)
		(fp_line
			(start 0.7874 -0.4064)
			(end 0.7874 0.4064)
			(stroke
				(width 0.1524)
				(type default)
			)
			(layer "F.SilkS")
		)
		(fp_line
			(start 0.7874 0.4064)
			(end -0.7874 0.4064)
			(stroke
				(width 0.1524)
				(type default)
			)
			(layer "F.SilkS")
		)
		(fp_line
			(start -0.67945 -0.305054)
			(end -0.12065 -0.305054)
			(stroke
				(width 0.1)
				(type default)
			)
			(layer "F.Fab")
		)
		(fp_line
			(start -0.67945 0.3048)
			(end -0.67945 -0.305054)
			(stroke
				(width 0.1)
				(type default)
			)
			(layer "F.Fab")
		)
		(fp_line
			(start -0.12065 -0.305054)
			(end -0.12065 -0.2794)
			(stroke
				(width 0.1)
				(type default)
			)
			(layer "F.Fab")
		)
		(fp_line
			(start -0.12065 -0.2794)
			(end 0.12065 -0.2794)
			(stroke
				(width 0.1)
				(type default)
			)
			(layer "F.Fab")
		)
		(fp_line
			(start -0.12065 0.2794)
			(end -0.12065 0.3048)
			(stroke
				(width 0.1)
				(type default)
			)
			(layer "F.Fab")
		)
		(fp_line
			(start -0.12065 0.3048)
			(end -0.67945 0.3048)
			(stroke
				(width 0.1)
				(type default)
			)
			(layer "F.Fab")
		)
		(fp_line
			(start 0.120396 0.2794)
			(end -0.12065 0.2794)
			(stroke
				(width 0.1)
				(type default)
			)
			(layer "F.Fab")
		)
		(fp_line
			(start 0.120396 0.3048)
			(end 0.120396 0.2794)
			(stroke
				(width 0.1)
				(type default)
			)
			(layer "F.Fab")
		)
		(fp_line
			(start 0.12065 -0.3048)
			(end 0.67945 -0.3048)
			(stroke
				(width 0.1)
				(type default)
			)
			(layer "F.Fab")
		)
		(fp_line
			(start 0.12065 -0.2794)
			(end 0.12065 -0.3048)
			(stroke
				(width 0.1)
				(type default)
			)
			(layer "F.Fab")
		)
		(fp_line
			(start 0.67945 -0.3048)
			(end 0.67945 0.3048)
			(stroke
				(width 0.1)
				(type default)
			)
			(layer "F.Fab")
		)
		(fp_line
			(start 0.67945 0.3048)
			(end 0.120396 0.3048)
			(stroke
				(width 0.1)
				(type default)
			)
			(layer "F.Fab")
		)
		(pad "1" smd circle
			(at -0.40005 0)
			(size 0 0)
			(layers "F.Cu" "F.Mask" "F.Paste")
			(net "SW_PVCCINFAON_CPU1_BOOT1_R")
		)
		(pad "2" smd circle
			(at 0.40005 0)
			(size 0 0)
			(layers "F.Cu" "F.Mask" "F.Paste")
			(net "SW_PVCCINFAON_CPU1_BOOTR1")
		)
	)
	(footprint ""
		(layer "F.Cu")
		(at 174.879 -411.9626)
		(property "Reference" "JP4003"
			(at 2.060448 3.252724 90)
			(unlocked yes)
			(layer "F.SilkS")
			(effects
				(font
					(size 0.7874 0.5842)
					(thickness 0.1524)
				)
				(justify left)
			)
		)
		(property "Value" ""
			(at 0 0 0)
			(layer "F.Fab")
			(effects
				(font
					(size 1.27 1.27)
				)
			)
		)
		(duplicate_pad_numbers_are_jumpers no)
		(fp_line
			(start -1.249934 -1.320038)
			(end 1.249934 -1.320038)
			(stroke
				(width 0.1524)
				(type default)
			)
			(layer "F.SilkS")
		)
		(fp_line
			(start -1.249934 6.400038)
			(end -1.249934 -1.320038)
			(stroke
				(width 0.1524)
				(type default)
			)
			(layer "F.SilkS")
		)
		(fp_line
			(start 1.249934 -1.320038)
			(end 1.249934 6.400038)
			(stroke
				(width 0.1524)
				(type default)
			)
			(layer "F.SilkS")
		)
		(fp_line
			(start 1.249934 6.400038)
			(end -1.249934 6.400038)
			(stroke
				(width 0.1524)
				(type default)
			)
			(layer "F.SilkS")
		)
		(fp_poly
			(pts
				(xy -1.452372 0) (xy -2.5654 0.556514) (xy -2.5654 -0.556514)
			)
			(stroke
				(width 0)
				(type default)
			)
			(fill yes)
			(layer "F.SilkS")
		)
		(fp_line
			(start -1.249934 -1.320038)
			(end 1.249934 -1.320038)
			(stroke
				(width 0.1)
				(type default)
			)
			(layer "F.Fab")
		)
		(fp_line
			(start -1.249934 6.400038)
			(end -1.249934 -1.320038)
			(stroke
				(width 0.1)
				(type default)
			)
			(layer "F.Fab")
		)
		(fp_line
			(start 1.249934 -1.320038)
			(end 1.249934 6.400038)
			(stroke
				(width 0.1)
				(type default)
			)
			(layer "F.Fab")
		)
		(fp_line
			(start 1.249934 6.400038)
			(end -1.249934 6.400038)
			(stroke
				(width 0.1)
				(type default)
			)
			(layer "F.Fab")
		)
		(fp_poly
			(pts
				(xy -2.5654 -0.556514) (xy -1.452372 0) (xy -2.5654 0.556514)
			)
			(stroke
				(width 0)
				(type default)
			)
			(fill yes)
			(layer "F.Fab")
		)
		(fp_text user "3"
			(at -1.909572 5.30225 180)
			(unlocked yes)
			(layer "F.SilkS")
			(effects
				(font
					(size 0.7874 0.5842)
					(thickness 0.1524)
				)
			)
		)
		(fp_text user "3"
			(at -1.502156 5.17271 180)
			(unlocked yes)
			(layer "B.SilkS")
			(effects
				(font
					(size 0.7874 0.5842)
					(thickness 0.1524)
				)
				(justify mirror)
			)
		)
		(fp_text user "1"
			(at -1.425956 -0.14351 180)
			(unlocked yes)
			(layer "B.SilkS")
			(effects
				(font
					(size 0.7874 0.5842)
					(thickness 0.1524)
				)
				(justify mirror)
			)
		)
		(fp_text user "3"
			(at -1.1557 5.18287 0)
			(unlocked yes)
			(layer "B.Fab")
			(effects
				(font
					(size 0.7874 0.5842)
					(thickness 0.1524)
				)
				(justify mirror)
			)
		)
		(fp_text user "1"
			(at -1.143 0.02667 0)
			(unlocked yes)
			(layer "B.Fab")
			(effects
				(font
					(size 0.7874 0.5842)
					(thickness 0.1524)
				)
				(justify mirror)
			)
		)
		(fp_text user "3"
			(at -1.778 5.13207 0)
			(unlocked yes)
			(layer "F.Fab")
			(effects
				(font
					(size 0.7874 0.5842)
					(thickness 0.1524)
				)
			)
		)
		(pad "1" thru_hole rect
			(at 0 0)
			(size 1.5494 1.5494)
			(drill 1.0414)
			(layers "*.Cu" "*.Mask")
			(remove_unused_layers no)
			(net "Net_1915")
			(clearance 0)
			(padstack
				(mode front_inner_back)
				(layer "Inner"
					(shape circle)
					(size 1.5494 1.5494)
					(clearance 0)
				)
				(layer "B.Cu"
					(shape rect)
					(size 1.5494 1.5494)
					(clearance 0)
				)
			)
		)
		(pad "2" thru_hole circle
			(at 0 2.54)
			(size 1.5494 1.5494)
			(drill 1.0414)
			(layers "*.Cu" "*.Mask")
			(remove_unused_layers no)
			(net "PDB_PRSNT_N")
			(clearance 0)
		)
		(pad "3" thru_hole circle
			(at 0 5.08)
			(size 1.5494 1.5494)
			(drill 1.0414)
			(layers "*.Cu" "*.Mask")
			(remove_unused_layers no)
			(net "GND")
			(clearance 0)
		)
	)
	(footprint ""
		(layer "F.Cu")
		(at 303.48809 -428.85106)
		(property "Reference" "R4577"
			(at 0 0 0)
			(layer "F.SilkS")
			(hide yes)
			(effects
				(font
					(size 1.27 1.27)
				)
			)
		)
		(property "Value" ""
			(at 0 0 0)
			(layer "F.Fab")
			(effects
				(font
					(size 1.27 1.27)
				)
			)
		)
		(duplicate_pad_numbers_are_jumpers no)
		(fp_line
			(start -0.7874 -0.4064)
			(end 0.7874 -0.4064)
			(stroke
				(width 0.1524)
				(type default)
			)
			(layer "F.SilkS")
		)
		(fp_line
			(start -0.7874 0.4064)
			(end -0.7874 -0.4064)
			(stroke
				(width 0.1524)
				(type default)
			)
			(layer "F.SilkS")
		)
		(fp_line
			(start 0.7874 -0.4064)
			(end 0.7874 0.4064)
			(stroke
				(width 0.1524)
				(type default)
			)
			(layer "F.SilkS")
		)
		(fp_line
			(start 0.7874 0.4064)
			(end -0.7874 0.4064)
			(stroke
				(width 0.1524)
				(type default)
			)
			(layer "F.SilkS")
		)
		(fp_line
			(start -0.67945 -0.305054)
			(end -0.12065 -0.305054)
			(stroke
				(width 0.1)
				(type default)
			)
			(layer "F.Fab")
		)
		(fp_line
			(start -0.67945 0.3048)
			(end -0.67945 -0.305054)
			(stroke
				(width 0.1)
				(type default)
			)
			(layer "F.Fab")
		)
		(fp_line
			(start -0.12065 -0.305054)
			(end -0.12065 -0.2794)
			(stroke
				(width 0.1)
				(type default)
			)
			(layer "F.Fab")
		)
		(fp_line
			(start -0.12065 -0.2794)
			(end 0.12065 -0.2794)
			(stroke
				(width 0.1)
				(type default)
			)
			(layer "F.Fab")
		)
		(fp_line
			(start -0.12065 0.2794)
			(end -0.12065 0.3048)
			(stroke
				(width 0.1)
				(type default)
			)
			(layer "F.Fab")
		)
		(fp_line
			(start -0.12065 0.3048)
			(end -0.67945 0.3048)
			(stroke
				(width 0.1)
				(type default)
			)
			(layer "F.Fab")
		)
		(fp_line
			(start 0.120396 0.2794)
			(end -0.12065 0.2794)
			(stroke
				(width 0.1)
				(type default)
			)
			(layer "F.Fab")
		)
		(fp_line
			(start 0.120396 0.3048)
			(end 0.120396 0.2794)
			(stroke
				(width 0.1)
				(type default)
			)
			(layer "F.Fab")
		)
		(fp_line
			(start 0.12065 -0.3048)
			(end 0.67945 -0.3048)
			(stroke
				(width 0.1)
				(type default)
			)
			(layer "F.Fab")
		)
		(fp_line
			(start 0.12065 -0.2794)
			(end 0.12065 -0.3048)
			(stroke
				(width 0.1)
				(type default)
			)
			(layer "F.Fab")
		)
		(fp_line
			(start 0.67945 -0.3048)
			(end 0.67945 0.3048)
			(stroke
				(width 0.1)
				(type default)
			)
			(layer "F.Fab")
		)
		(fp_line
			(start 0.67945 0.3048)
			(end 0.120396 0.3048)
			(stroke
				(width 0.1)
				(type default)
			)
			(layer "F.Fab")
		)
		(pad "1" smd circle
			(at -0.40005 0)
			(size 0 0)
			(layers "F.Cu" "F.Mask" "F.Paste")
			(net "GPU_3V3IO_RSVD3_FFU")
		)
		(pad "2" smd circle
			(at 0.40005 0)
			(size 0 0)
			(layers "F.Cu" "F.Mask" "F.Paste")
			(net "GPU_3V3IO_RSVD3_FFU_ISO")
		)
	)
)
